# S9S_MB_2U (Grand Teton) — schematic netlist excerpt (pin names and nets, part order shuffled) for the footprints in the layout excerpt that follows; sources: Cadence DE-HDL packaged netlist, KiCad conversion of 03242023_DA0F0TMBIJ0_F0T_Motherboard_J_brd_V01_OCP.brd

R4130  Q_RES  4.7K 5% CHIP  pkg 0402LF  page 146 : A = P3V3_AUX ; B = GPU_3V3IO_RSVD1_FFU_ISO
C2255  Q_CAP  8.2PF 50V 0.1P NP0  pkg C0402  page 212 : A = CLK_GEN2_XTAL_IN_R ; B = GND

(kicad_pcb
	(version 20260206)
	(generator "pcbnew")
	(generator_version "10.0")
	(general
		(thickness 1.6)
		(legacy_teardrops no)
	)
	(paper "A4")
	(title_block
		(title "03242023_DA0F0TMBIJ0_F0T_Motherboard_J_brd_V01_OCP.brd")
		(comment 1 "Grand Teton / footprints 3346-3347 of 6105")
	)
	(layers
		(0 "F.Cu" signal "TOP")
		(4 "In1.Cu" signal "GND")
		(6 "In2.Cu" signal "IN1")
		(8 "In3.Cu" signal "GND1")
		(10 "In4.Cu" signal "IN2")
		(12 "In5.Cu" signal "GND2")
		(14 "In6.Cu" signal "IN3")
		(16 "In7.Cu" signal "GND3")
		(18 "In8.Cu" signal "VCC")
		(20 "In9.Cu" signal "VCC1")
		(22 "In10.Cu" signal "GND4")
		(24 "In11.Cu" signal "IN4")
		(26 "In12.Cu" signal "GND5")
		(28 "In13.Cu" signal "IN5")
		(30 "In14.Cu" signal "GND6")
		(32 "In15.Cu" signal "IN6")
		(34 "In16.Cu" signal "GND7")
		(2 "B.Cu" signal "BOTTOM")
		(9 "F.Adhes" user "F.Adhesive")
		(11 "B.Adhes" user "B.Adhesive")
		(13 "F.Paste" user "Package Geometry/Pastemask Top")
		(15 "B.Paste" user "Package Geometry/Pastemask Bottom")
		(5 "F.SilkS" user "Ref Des/Silkscreen Top")
		(7 "B.SilkS" user "Ref Des/Silkscreen Bottom")
		(1 "F.Mask" user "Board Geometry/Soldermask Top")
		(3 "B.Mask" user "Board Geometry/Soldermask Bottom")
		(17 "Dwgs.User" user "User.Drawings")
		(19 "Cmts.User" user "User.Comments")
		(21 "Eco1.User" user "User.Eco1")
		(23 "Eco2.User" user "User.Eco2")
		(25 "Edge.Cuts" user "Board Geometry/Outline")
		(27 "Margin" user)
		(31 "F.CrtYd" user "Package Geometry/Place Bound Top")
		(29 "B.CrtYd" user "Package Geometry/Place Bound Bottom")
		(35 "F.Fab" user "Ref Des/Assembly Top")
		(33 "B.Fab" user "Ref Des/Assembly Bottom")
	)
	(footprint ""
		(layer "F.Cu")
		(at 309.57774 -433.12461 90)
		(property "Reference" "R4130"
			(at 0 0 90)
			(layer "F.SilkS")
			(hide yes)
			(effects
				(font
					(size 1.27 1.27)
				)
			)
		)
		(property "Value" ""
			(at 0 0 90)
			(layer "F.Fab")
			(effects
				(font
					(size 1.27 1.27)
				)
			)
		)
		(duplicate_pad_numbers_are_jumpers no)
		(fp_line
			(start 0.7874 -0.4064)
			(end 0.7874 0.4064)
			(stroke
				(width 0.1524)
				(type default)
			)
			(layer "F.SilkS")
		)
		(fp_line
			(start -0.7874 -0.4064)
			(end 0.7874 -0.4064)
			(stroke
				(width 0.1524)
				(type default)
			)
			(layer "F.SilkS")
		)
		(fp_line
			(start 0.7874 0.4064)
			(end -0.7874 0.4064)
			(stroke
				(width 0.1524)
				(type default)
			)
			(layer "F.SilkS")
		)
		(fp_line
			(start -0.7874 0.4064)
			(end -0.7874 -0.4064)
			(stroke
				(width 0.1524)
				(type default)
			)
			(layer "F.SilkS")
		)
		(fp_line
			(start -0.12065 -0.305054)
			(end -0.12065 -0.2794)
			(stroke
				(width 0.1)
				(type default)
			)
			(layer "F.Fab")
		)
		(fp_line
			(start -0.67945 -0.305054)
			(end -0.12065 -0.305054)
			(stroke
				(width 0.1)
				(type default)
			)
			(layer "F.Fab")
		)
		(fp_line
			(start 0.67945 -0.3048)
			(end 0.67945 0.3048)
			(stroke
				(width 0.1)
				(type default)
			)
			(layer "F.Fab")
		)
		(fp_line
			(start 0.12065 -0.3048)
			(end 0.67945 -0.3048)
			(stroke
				(width 0.1)
				(type default)
			)
			(layer "F.Fab")
		)
		(fp_line
			(start 0.12065 -0.2794)
			(end 0.12065 -0.3048)
			(stroke
				(width 0.1)
				(type default)
			)
			(layer "F.Fab")
		)
		(fp_line
			(start -0.12065 -0.2794)
			(end 0.12065 -0.2794)
			(stroke
				(width 0.1)
				(type default)
			)
			(layer "F.Fab")
		)
		(fp_line
			(start 0.120396 0.2794)
			(end -0.12065 0.2794)
			(stroke
				(width 0.1)
				(type default)
			)
			(layer "F.Fab")
		)
		(fp_line
			(start -0.12065 0.2794)
			(end -0.12065 0.3048)
			(stroke
				(width 0.1)
				(type default)
			)
			(layer "F.Fab")
		)
		(fp_line
			(start 0.67945 0.3048)
			(end 0.120396 0.3048)
			(stroke
				(width 0.1)
				(type default)
			)
			(layer "F.Fab")
		)
		(fp_line
			(start 0.120396 0.3048)
			(end 0.120396 0.2794)
			(stroke
				(width 0.1)
				(type default)
			)
			(layer "F.Fab")
		)
		(fp_line
			(start -0.12065 0.3048)
			(end -0.67945 0.3048)
			(stroke
				(width 0.1)
				(type default)
			)
			(layer "F.Fab")
		)
		(fp_line
			(start -0.67945 0.3048)
			(end -0.67945 -0.305054)
			(stroke
				(width 0.1)
				(type default)
			)
			(layer "F.Fab")
		)
		(pad "1" smd circle
			(at -0.40005 0 90)
			(size 0 0)
			(layers "F.Cu" "F.Mask" "F.Paste")
			(net "P3V3_AUX")
		)
		(pad "2" smd circle
			(at 0.40005 0 90)
			(size 0 0)
			(layers "F.Cu" "F.Mask" "F.Paste")
			(net "GPU_3V3IO_RSVD1_FFU_ISO")
		)
	)
	(footprint ""
		(layer "F.Cu")
		(at 240.60785 -248.515378 -90)
		(property "Reference" "C2255"
			(at 0 0 270)
			(layer "F.SilkS")
			(hide yes)
			(effects
				(font
					(size 1.27 1.27)
				)
			)
		)
		(property "Value" ""
			(at 0 0 270)
			(layer "F.Fab")
			(effects
				(font
					(size 1.27 1.27)
				)
			)
		)
		(duplicate_pad_numbers_are_jumpers no)
		(fp_line
			(start -0.7874 0.4064)
			(end -0.7874 -0.4064)
			(stroke
				(width 0.1524)
				(type default)
			)
			(layer "F.SilkS")
		)
		(fp_line
			(start 0.7874 0.4064)
			(end -0.7874 0.4064)
			(stroke
				(width 0.1524)
				(type default)
			)
			(layer "F.SilkS")
		)
		(fp_line
			(start -0.7874 -0.4064)
			(end 0.7874 -0.4064)
			(stroke
				(width 0.1524)
				(type default)
			)
			(layer "F.SilkS")
		)
		(fp_line
			(start 0.7874 -0.4064)
			(end 0.7874 0.4064)
			(stroke
				(width 0.1524)
				(type default)
			)
			(layer "F.SilkS")
		)
		(fp_line
			(start -0.67945 0.3048)
			(end -0.67945 -0.305054)
			(stroke
				(width 0.1)
				(type default)
			)
			(layer "F.Fab")
		)
		(fp_line
			(start -0.12065 0.3048)
			(end -0.67945 0.3048)
			(stroke
				(width 0.1)
				(type default)
			)
			(layer "F.Fab")
		)
		(fp_line
			(start 0.120396 0.3048)
			(end 0.120396 0.2794)
			(stroke
				(width 0.1)
				(type default)
			)
			(layer "F.Fab")
		)
		(fp_line
			(start 0.67945 0.3048)
			(end 0.120396 0.3048)
			(stroke
				(width 0.1)
				(type default)
			)
			(layer "F.Fab")
		)
		(fp_line
			(start -0.12065 0.2794)
			(end -0.12065 0.3048)
			(stroke
				(width 0.1)
				(type default)
			)
			(layer "F.Fab")
		)
		(fp_line
			(start 0.120396 0.2794)
			(end -0.12065 0.2794)
			(stroke
				(width 0.1)
				(type default)
			)
			(layer "F.Fab")
		)
		(fp_line
			(start -0.12065 -0.2794)
			(end 0.12065 -0.2794)
			(stroke
				(width 0.1)
				(type default)
			)
			(layer "F.Fab")
		)
		(fp_line
			(start 0.12065 -0.2794)
			(end 0.12065 -0.3048)
			(stroke
				(width 0.1)
				(type default)
			)
			(layer "F.Fab")
		)
		(fp_line
			(start 0.12065 -0.3048)
			(end 0.67945 -0.3048)
			(stroke
				(width 0.1)
				(type default)
			)
			(layer "F.Fab")
		)
		(fp_line
			(start 0.67945 -0.3048)
			(end 0.67945 0.3048)
			(stroke
				(width 0.1)
				(type default)
			)
			(layer "F.Fab")
		)
		(fp_line
			(start -0.67945 -0.305054)
			(end -0.12065 -0.305054)
			(stroke
				(width 0.1)
				(type default)
			)
			(layer "F.Fab")
		)
		(fp_line
			(start -0.12065 -0.305054)
			(end -0.12065 -0.2794)
			(stroke
				(width 0.1)
				(type default)
			)
			(layer "F.Fab")
		)
		(pad "1" smd circle
			(at -0.40005 0 270)
			(size 0 0)
			(layers "F.Cu" "F.Mask" "F.Paste")
			(net "CLK_GEN2_XTAL_IN_R")
		)
		(pad "2" smd circle
			(at 0.40005 0 270)
			(size 0 0)
			(layers "F.Cu" "F.Mask" "F.Paste")
			(net "GND")
		)
	)
)
